(kicad_pcb
	(version 20260206)
	(generator "pcbnew")
	(generator_version "10.0")
	(general
		(thickness 1.6)
		(legacy_teardrops no)
	)
	(paper "A4")
	(title_block
		(title "v1-tray-backplane — T6M_tray_BP_c_1023_1120.brd")
		(comment 1 "Open CloudServer (Microsoft) / footprints 131-133 of 170")
	)
	(layers
		(0 "F.Cu" signal "TOP")
		(4 "In1.Cu" signal "GND")
		(6 "In2.Cu" signal "IN1")
		(8 "In3.Cu" signal "VCC")
		(10 "In4.Cu" signal "VCC1")
		(12 "In5.Cu" signal "IN2")
		(14 "In6.Cu" signal "GND1")
		(2 "B.Cu" signal "BOTTOM")
		(9 "F.Adhes" user "F.Adhesive")
		(11 "B.Adhes" user "B.Adhesive")
		(13 "F.Paste" user "Package Geometry/Pastemask Top")
		(15 "B.Paste" user "Package Geometry/Pastemask Bottom")
		(5 "F.SilkS" user "Ref Des/Silkscreen Top")
		(7 "B.SilkS" user "Ref Des/Silkscreen Bottom")
		(1 "F.Mask" user "Board Geometry/Soldermask Top")
		(3 "B.Mask" user "Board Geometry/Soldermask Bottom")
		(17 "Dwgs.User" user "User.Drawings")
		(19 "Cmts.User" user "User.Comments")
		(21 "Eco1.User" user "User.Eco1")
		(23 "Eco2.User" user "User.Eco2")
		(25 "Edge.Cuts" user "Board Geometry/Outline")
		(27 "Margin" user)
		(31 "F.CrtYd" user "Package Geometry/Place Bound Top")
		(29 "B.CrtYd" user "Package Geometry/Place Bound Bottom")
		(35 "F.Fab" user "Ref Des/Assembly Top")
		(33 "B.Fab" user "Ref Des/Assembly Bottom")
	)
	(footprint ""
		(layer "F.Cu")
		(at 88.017096 -23.621746 -90)
		(property "Reference" "C2"
			(at -1.092708 4.608322 90)
			(unlocked yes)
			(layer "F.SilkS")
			(effects
				(font
					(size 0.7874 0.5842)
					(thickness 0.1524)
				)
			)
		)
		(property "Value" ""
			(at 0 0 270)
			(layer "F.Fab")
			(effects
				(font
					(size 1.27 1.27)
				)
			)
		)
		(duplicate_pad_numbers_are_jumpers no)
		(fp_line
			(start -1.2954 0.5842)
			(end -1.2954 -0.5842)
			(stroke
				(width 0.1524)
				(type default)
			)
			(layer "F.SilkS")
		)
		(fp_line
			(start 1.2954 0.5842)
			(end -1.2954 0.5842)
			(stroke
				(width 0.1524)
				(type default)
			)
			(layer "F.SilkS")
		)
		(fp_line
			(start -1.2954 -0.5842)
			(end 1.2954 -0.5842)
			(stroke
				(width 0.1524)
				(type default)
			)
			(layer "F.SilkS")
		)
		(fp_line
			(start 0 -0.5842)
			(end 0 0.5842)
			(stroke
				(width 0.1524)
				(type default)
			)
			(layer "F.SilkS")
		)
		(fp_line
			(start 1.2954 -0.5842)
			(end 1.2954 0.5842)
			(stroke
				(width 0.1524)
				(type default)
			)
			(layer "F.SilkS")
		)
		(fp_poly
			(pts
				(xy 0.8636 -0.4572) (xy 0.8636 -0.3556) (xy 1.143 -0.3556) (xy 1.143 0.3556) (xy 0.8636 0.3556)
				(xy 0.8636 0.4572) (xy -0.8636 0.4572) (xy -0.8636 0.3556) (xy -1.143 0.3556) (xy -1.143 -0.3556)
				(xy -0.8636 -0.3556) (xy -0.8636 -0.4572)
			)
			(stroke
				(width 0)
				(type default)
			)
			(fill no)
			(layer "F.CrtYd")
		)
		(fp_line
			(start -0.884936 0.504952)
			(end -0.884936 -0.504952)
			(stroke
				(width 0.1)
				(type default)
			)
			(layer "F.Fab")
		)
		(fp_line
			(start 0.884936 0.504952)
			(end -0.884936 0.504952)
			(stroke
				(width 0.1)
				(type default)
			)
			(layer "F.Fab")
		)
		(fp_line
			(start -0.884936 -0.504952)
			(end 0.884936 -0.504952)
			(stroke
				(width 0.1)
				(type default)
			)
			(layer "F.Fab")
		)
		(fp_line
			(start 0.884936 -0.504952)
			(end 0.884936 0.504952)
			(stroke
				(width 0.1)
				(type default)
			)
			(layer "F.Fab")
		)
		(pad "1" smd rect
			(at 0.7366 0)
			(size 0.7112 0.8128)
			(layers "F.Cu" "F.Mask" "F.Paste")
			(net "P12V")
		)
		(pad "2" smd rect
			(at -0.7366 0)
			(size 0.7112 0.8128)
			(layers "F.Cu" "F.Mask" "F.Paste")
			(net "GND")
		)
	)
	(footprint ""
		(layer "F.Cu")
		(at 77.920088 -10.6299)
		(property "Reference" "J11"
			(at -5.4102 -11.267948 0)
			(unlocked yes)
			(layer "F.SilkS")
			(effects
				(font
					(size 0.7874 0.5842)
					(thickness 0.1524)
				)
				(justify left)
			)
		)
		(property "Value" ""
			(at 0 0 0)
			(layer "F.Fab")
			(effects
				(font
					(size 1.27 1.27)
				)
			)
		)
		(duplicate_pad_numbers_are_jumpers no)
		(fp_line
			(start -5.32511 -10.500106)
			(end -5.32511 0)
			(stroke
				(width 0.1524)
				(type default)
			)
			(layer "F.SilkS")
		)
		(fp_line
			(start -5.32511 0)
			(end -5.32511 43.029886)
			(stroke
				(width 0.1524)
				(type default)
			)
			(layer "F.SilkS")
		)
		(fp_line
			(start -5.32511 13.129768)
			(end 5.32511 13.129768)
			(stroke
				(width 0.1524)
				(type default)
			)
			(layer "F.SilkS")
		)
		(fp_line
			(start -5.32511 43.029886)
			(end 5.32511 43.029886)
			(stroke
				(width 0.1524)
				(type default)
			)
			(layer "F.SilkS")
		)
		(fp_line
			(start 5.32511 -10.500106)
			(end -5.32511 -10.500106)
			(stroke
				(width 0.1524)
				(type default)
			)
			(layer "F.SilkS")
		)
		(fp_line
			(start 5.32511 43.029886)
			(end 5.32511 -10.500106)
			(stroke
				(width 0.1524)
				(type default)
			)
			(layer "F.SilkS")
		)
		(fp_poly
			(pts
				(xy -7.86638 -0.8636) (xy -7.86638 0.9398) (xy -7.86638 0.951484) (xy -6.11378 0)
			)
			(stroke
				(width 0)
				(type default)
			)
			(fill yes)
			(layer "F.SilkS")
		)
		(fp_poly
			(pts
				(arc
					(start 2.758694 0)
					(mid -2.758694 0)
					(end 2.758694 0)
				)
			)
			(stroke
				(width 0)
				(type default)
			)
			(fill no)
			(layer "B.CrtYd")
		)
		(fp_poly
			(pts
				(arc
					(start 2.758694 5.62991)
					(mid -2.758694 5.62991)
					(end 2.758694 5.62991)
				)
			)
			(stroke
				(width 0)
				(type default)
			)
			(fill no)
			(layer "B.CrtYd")
		)
		(fp_poly
			(pts
				(arc
					(start 2.95275 -6.620002)
					(mid -2.95275 -6.620002)
					(end 2.95275 -6.620002)
				)
			)
			(stroke
				(width 0)
				(type default)
			)
			(fill no)
			(layer "B.CrtYd")
		)
		(fp_poly
			(pts
				(xy -5.32511 0) (xy -5.32511 43.029886) (xy 5.32511 43.029886) (xy 5.32511 -10.500106) (xy -5.32511 -10.500106)
			)
			(stroke
				(width 0)
				(type default)
			)
			(fill no)
			(layer "F.CrtYd")
		)
		(fp_line
			(start -5.32511 -10.500106)
			(end -5.32511 0)
			(stroke
				(width 0.1)
				(type default)
			)
			(layer "F.Fab")
		)
		(fp_line
			(start -5.32511 0)
			(end -5.32511 43.029886)
			(stroke
				(width 0.1)
				(type default)
			)
			(layer "F.Fab")
		)
		(fp_line
			(start -5.32511 13.129768)
			(end 5.32511 13.129768)
			(stroke
				(width 0.1)
				(type default)
			)
			(layer "F.Fab")
		)
		(fp_line
			(start -5.32511 43.029886)
			(end 5.32511 43.029886)
			(stroke
				(width 0.1)
				(type default)
			)
			(layer "F.Fab")
		)
		(fp_line
			(start 5.32511 -10.500106)
			(end -5.32511 -10.500106)
			(stroke
				(width 0.1)
				(type default)
			)
			(layer "F.Fab")
		)
		(fp_line
			(start 5.32511 43.029886)
			(end 5.32511 -10.500106)
			(stroke
				(width 0.1)
				(type default)
			)
			(layer "F.Fab")
		)
		(fp_poly
			(pts
				(xy -7.86638 -0.8636) (xy -7.86638 0.9398) (xy -7.86638 0.951484) (xy -6.11378 0)
			)
			(stroke
				(width 0)
				(type default)
			)
			(fill yes)
			(layer "F.Fab")
		)
		(fp_text user "1"
			(at -6.031484 -0.039116 0)
			(unlocked yes)
			(layer "F.SilkS")
			(effects
				(font
					(size 0.7874 0.5842)
					(thickness 0.1524)
				)
				(justify left)
			)
		)
		(fp_text user "1"
			(at -2.9464 0.043688 0)
			(unlocked yes)
			(layer "B.SilkS")
			(effects
				(font
					(size 0.7874 0.5842)
					(thickness 0.1524)
				)
				(justify left mirror)
			)
		)
		(fp_text user "1"
			(at -2.9464 0.043688 0)
			(unlocked yes)
			(layer "B.Fab")
			(effects
				(font
					(size 0.7874 0.5842)
					(thickness 0.000001)
				)
				(justify left mirror)
			)
		)
		(fp_text user "1"
			(at -6.031484 -0.039116 0)
			(unlocked yes)
			(layer "F.Fab")
			(effects
				(font
					(size 0.7874 0.5842)
					(thickness 0.000001)
				)
				(justify left)
			)
		)
		(pad "1" thru_hole circle
			(at 0 0)
			(size 5.4102 5.4102)
			(drill 4.0132)
			(layers "*.Cu" "*.Mask")
			(remove_unused_layers no)
			(net "GND")
			(clearance -0.4445)
		)
		(pad "2" thru_hole circle
			(at 0 5.62991)
			(size 5.4102 5.4102)
			(drill 4.0132)
			(layers "*.Cu" "*.Mask")
			(remove_unused_layers no)
			(net "GND")
			(clearance -0.4445)
		)
		(pad "3" thru_hole circle
			(at 0 -6.620002)
			(size 5.7912 5.7912)
			(drill 4.0132)
			(layers "*.Cu" "*.Mask")
			(remove_unused_layers no)
			(net "GND")
			(clearance -0.635)
		)
	)
	(footprint ""
		(layer "F.Cu")
		(at 117.31244 -24.36241)
		(property "Reference" "R8"
			(at -61.341 5.115052 0)
			(unlocked yes)
			(layer "F.SilkS")
			(effects
				(font
					(size 0.7874 0.5842)
					(thickness 0.1524)
				)
				(justify left)
			)
		)
		(property "Value" ""
			(at 0 0 0)
			(layer "F.Fab")
			(effects
				(font
					(size 1.27 1.27)
				)
			)
		)
		(duplicate_pad_numbers_are_jumpers no)
		(fp_line
			(start -0.7874 -0.4064)
			(end 0.7874 -0.4064)
			(stroke
				(width 0.1524)
				(type default)
			)
			(layer "F.SilkS")
		)
		(fp_line
			(start -0.7874 0.4064)
			(end -0.7874 -0.4064)
			(stroke
				(width 0.1524)
				(type default)
			)
			(layer "F.SilkS")
		)
		(fp_line
			(start 0.7874 -0.4064)
			(end 0.7874 0.4064)
			(stroke
				(width 0.1524)
				(type default)
			)
			(layer "F.SilkS")
		)
		(fp_line
			(start 0.7874 0.4064)
			(end -0.7874 0.4064)
			(stroke
				(width 0.1524)
				(type default)
			)
			(layer "F.SilkS")
		)
		(fp_poly
			(pts
				(xy -0.508 0.2794) (xy -0.508 0.2286) (xy -0.635 0.2286) (xy -0.635 -0.254) (xy -0.5334 -0.254)
				(xy -0.5334 -0.2794) (xy 0.5334 -0.2794) (xy 0.5334 -0.254) (xy 0.635 -0.254) (xy 0.635 0.254) (xy 0.5334 0.254)
				(xy 0.5334 0.2794)
			)
			(stroke
				(width 0)
				(type default)
			)
			(fill no)
			(layer "F.CrtYd")
		)
		(pad "1" smd rect
			(at 0.40005 0)
			(size 0.4572 0.508)
			(layers "F.Cu" "F.Mask" "F.Paste")
			(net "P3V3_BLAD1")
		)
		(pad "2" smd rect
			(at -0.40005 0)
			(size 0.4572 0.508)
			(layers "F.Cu" "F.Mask" "F.Paste")
			(net "ENET10G_2_SCL")
		)
	)
)
